FILE_TYPE = MACRO_DRAWING;
SET COLOR_WIRE YELLOW;
SET COLOR_PROP ORANGE;
SET COLOR_DOT WHITE;
SET COLOR_ARC YELLOW;
SET COLOR_BODY GREEN;
SET COLOR_NOTE PURPLE;
SET PROP_DISPLAY VALUE;
SET PAGE_NUMBER P327;
FORCEADD NCT7718W..1
(3200 250);
FORCEPROP 1 LAST PART_NUMBER AL007718001
J 0
(2955 584);
DISPLAY 0.723404 (2955 584);
PAINT GREEN (2955 584);
DISPLAY INVISIBLE (2955 584);
FORCEPROP 1 LAST MATERIAL EMPTY
J 0
(2955 457);
DISPLAY 0.723404 (2955 457);
PAINT GREEN (2955 457);
FORCEPROP 2 LAST ROOM HSC1_BOM2
J 0
(2950 700);
DISPLAY 1.021277 (2950 700);
FORCEPROP 2 LAST PART_TYPE SMLF
J 0
(2950 -100);
DISPLAY 0.510638 (2950 -100);
PAINT GREEN (2950 -100);
FORCEPROP 2 LAST VALUE NCT7718W
J 0
(2950 0);
DISPLAY 0.510638 (2950 0);
PAINT GREEN (2950 0);
FORCEPROP 1 LAST LOCATION U345
J 0
(2950 650);
DISPLAY 0.723404 (2950 650);
PAINT GREEN (2950 650);
FORCEPROP 0 LASTPIN (3600 200) $PN 6
J 0
(3610 210);
DISPLAY 0.680851 (3610 210);
PAINT MONO (3610 210);
FORCEPROP 0 LASTPIN (2800 300) $PN 2
J 2
(2790 310);
DISPLAY 0.680851 (2790 310);
PAINT MONO (2790 310);
FORCEPROP 0 LASTPIN (2800 200) $PN 3
J 2
(2790 210);
DISPLAY 0.680851 (2790 210);
PAINT MONO (2790 210);
FORCEPROP 0 LASTPIN (3600 100) $PN 5
J 0
(3610 110);
DISPLAY 0.680851 (3610 110);
PAINT MONO (3610 110);
FORCEPROP 0 LASTPIN (3600 400) $PN 8
J 0
(3610 410);
DISPLAY 0.680851 (3610 410);
PAINT MONO (3610 410);
FORCEPROP 0 LASTPIN (3600 300) $PN 7
J 0
(3610 310);
DISPLAY 0.680851 (3610 310);
PAINT MONO (3610 310);
FORCEPROP 0 LASTPIN (2800 100) $PN 4
J 2
(2790 110);
DISPLAY 0.680851 (2790 110);
PAINT MONO (2790 110);
FORCEPROP 0 LASTPIN (2800 400) $PN 1
J 2
(2790 410);
DISPLAY 0.680851 (2790 410);
PAINT MONO (2790 410);
FORCEPROP 1 LAST NEEDS_NO_SIZE TRUE
J 0
(3200 250);
DISPLAY 0.723404 (3200 250);
PAINT GREEN (3200 250);
DISPLAY INVISIBLE (3200 250);
FORCEPROP 2 LAST CDS_LIB pure_quanta
J 0
(3200 250);
DISPLAY INVISIBLE (3200 250);
FORCEPROP 1 LAST CDS_LMAN_SYM_OUTLINE -250,200,250,-200
J 0
(3200 250);
DISPLAY 0.468085 (3200 250);
PAINT GREEN (3200 250);
DISPLAY INVISIBLE (3200 250);
FORCEPROP 1 LAST PATH I10
J 0
(3200 250);
DISPLAY 0.723404 (3200 250);
PAINT GREEN (3200 250);
DISPLAY INVISIBLE (3200 250);
FORCEPROP 0 LAST $SEC 1
J 0
(2975 775);
DISPLAY 0.680851 (2975 775);
PAINT MONO (2975 775);
DISPLAY INVISIBLE (2975 775);
FORCEPROP 0 LAST CDS_SEC 1
J 0
(3000 800);
DISPLAY 1.021277 (3000 800);
DISPLAY INVISIBLE (3000 800);
FORCEADD Q_RES..1
(3425 -325);
FORCEPROP 1 LAST PART_NUMBER CS00002JB13
J 0
(3300 -375);
DISPLAY 0.319149 (3300 -375);
DISPLAY INVISIBLE (3300 -375);
FORCEPROP 2 LAST ROOM HSC1_BOM2
J 0
(3225 -275);
DISPLAY 1.021277 (3225 -275);
FORCEPROP 1 LAST PACK_TYPE 0402LF
J 0
(3300 -350);
DISPLAY 0.319149 (3300 -350);
FORCEPROP 1 LAST MATERIAL EMPTY
J 0
(3650 -325);
DISPLAY 0.404255 (3650 -325);
FORCEPROP 1 LAST WATTAGE 1/16W
J 2
(3550 -350);
DISPLAY 0.319149 (3550 -350);
FORCEPROP 1 LAST VALUE 0
J 2
(3575 -325);
DISPLAY 0.404255 (3575 -325);
FORCEPROP 1 LAST TOLERANCE 5%
J 0
(3600 -325);
DISPLAY 0.404255 (3600 -325);
FORCEPROP 1 LAST LOCATION R4896
J 0
(3225 -325);
DISPLAY 0.553191 (3225 -325);
FORCEPROP 1 LASTPIN (3325 -325) $PN 1
J 0
(3337 -313);
DISPLAY 0.808511 (3337 -313);
PAINT WHITE (3337 -313);
FORCEPROP 1 LASTPIN (3525 -325) $PN 2
J 0
(3487 -313);
DISPLAY 0.808511 (3487 -313);
PAINT WHITE (3487 -313);
FORCEPROP 2 LAST CDS_LIB pure_quanta
J 0
(3425 -325);
DISPLAY INVISIBLE (3425 -325);
FORCEPROP 1 LAST PATH I11
J 0
(3375 -175);
DISPLAY 0.978723 (3375 -175);
PAINT WHITE (3375 -175);
DISPLAY INVISIBLE (3375 -175);
FORCEPROP 0 LAST $SEC 1
J 0
(3525 -250);
DISPLAY 0.680851 (3525 -250);
PAINT MONO (3525 -250);
DISPLAY INVISIBLE (3525 -250);
FORCEPROP 0 LAST CDS_SEC 1
J 0
(3525 -250);
DISPLAY 1.021277 (3525 -250);
DISPLAY INVISIBLE (3525 -250);
FORCEADD UNIVERSAL_GND..1
(3700 -25);
FORCEPROP 3 LASTPIN (3700 25) SIG_NAME GND\g
J 0
(3710 35);
DISPLAY 0.659574 (3710 35);
PAINT MONO (3710 35);
DISPLAY INVISIBLE (3710 35);
FORCEPROP 1 LAST PATH I13
J 0
(3775 -25);
DISPLAY 0.872340 (3775 -25);
PAINT AQUA (3775 -25);
DISPLAY INVISIBLE (3775 -25);
FORCEPROP 2 LAST CDS_LIB logical_power
J 0
(3700 -25);
DISPLAY INVISIBLE (3700 -25);
FORCEPROP 1 LAST HDL_POWER GND
J 1
(3725 -100);
DISPLAY 0.702128 (3725 -100);
PAINT GREEN (3725 -100);
DISPLAY INVISIBLE (3725 -100);
FORCEADD Q_RES..1
(4475 200);
FORCEPROP 1 LAST PART_NUMBER CS00002JB13
J 0
(4375 250);
DISPLAY 0.319149 (4375 250);
DISPLAY INVISIBLE (4375 250);
FORCEPROP 2 LAST ROOM HSC1_BOM2
J 0
(4275 125);
DISPLAY 1.021277 (4275 125);
FORCEPROP 1 LAST WATTAGE 1/16W
J 2
(4550 275);
DISPLAY 0.319149 (4550 275);
FORCEPROP 1 LAST MATERIAL EMPTY
J 0
(4700 200);
DISPLAY 0.404255 (4700 200);
FORCEPROP 1 LAST PACK_TYPE 0402LF
J 0
(4375 275);
DISPLAY 0.319149 (4375 275);
FORCEPROP 1 LAST VALUE 0
J 2
(4625 200);
DISPLAY 0.404255 (4625 200);
FORCEPROP 1 LAST TOLERANCE 5%
J 0
(4650 200);
DISPLAY 0.404255 (4650 200);
FORCEPROP 1 LAST $LOCATION R4684
J 0
(4275 200);
DISPLAY 0.638298 (4275 200);
FORCEPROP 1 LASTPIN (4375 200) $PN 1
J 0
(4387 212);
DISPLAY 0.787234 (4387 212);
PAINT MONO (4387 212);
FORCEPROP 1 LASTPIN (4575 200) $PN 2
J 0
(4537 212);
DISPLAY 0.787234 (4537 212);
PAINT MONO (4537 212);
FORCEPROP 2 LAST CDS_LIB pure_quanta
J 0
(4475 200);
DISPLAY INVISIBLE (4475 200);
FORCEPROP 1 LAST PATH I14
J 0
(4425 350);
DISPLAY 0.978723 (4425 350);
PAINT WHITE (4425 350);
DISPLAY INVISIBLE (4425 350);
FORCEPROP 0 LAST CDS_LOCATION R4684
J 0
(4550 300);
DISPLAY 1.021277 (4550 300);
DISPLAY INVISIBLE (4550 300);
FORCEPROP 0 LAST $SEC 1
J 0
(4550 300);
DISPLAY 0.680851 (4550 300);
PAINT MONO (4550 300);
DISPLAY INVISIBLE (4550 300);
FORCEPROP 0 LAST CDS_SEC 1
J 0
(4550 300);
DISPLAY 1.021277 (4550 300);
DISPLAY INVISIBLE (4550 300);
FORCEADD Q_RES..1
(4475 400);
FORCEPROP 1 LAST PART_NUMBER CS00002JB13
J 0
(4350 350);
DISPLAY 0.319149 (4350 350);
DISPLAY INVISIBLE (4350 350);
FORCEPROP 1 LAST MATERIAL EMPTY
J 0
(4700 400);
DISPLAY 0.404255 (4700 400);
FORCEPROP 2 LAST ROOM HSC1_BOM2
J 0
(4275 450);
DISPLAY 1.021277 (4275 450);
FORCEPROP 1 LAST WATTAGE 1/16W
J 2
(4600 375);
DISPLAY 0.319149 (4600 375);
FORCEPROP 1 LAST PACK_TYPE 0402LF
J 0
(4350 375);
DISPLAY 0.319149 (4350 375);
FORCEPROP 1 LAST VALUE 0
J 2
(4625 400);
DISPLAY 0.404255 (4625 400);
FORCEPROP 1 LAST TOLERANCE 5%
J 0
(4650 400);
DISPLAY 0.404255 (4650 400);
FORCEPROP 1 LAST LOCATION R4894
J 0
(4275 400);
DISPLAY 0.553191 (4275 400);
FORCEPROP 1 LASTPIN (4375 400) $PN 1
J 0
(4387 412);
DISPLAY 0.808511 (4387 412);
PAINT WHITE (4387 412);
FORCEPROP 1 LASTPIN (4575 400) $PN 2
J 0
(4537 412);
DISPLAY 0.808511 (4537 412);
PAINT WHITE (4537 412);
FORCEPROP 2 LAST CDS_LIB pure_quanta
J 0
(4475 400);
DISPLAY INVISIBLE (4475 400);
FORCEPROP 1 LAST PATH I15
J 0
(4425 550);
DISPLAY 0.978723 (4425 550);
PAINT WHITE (4425 550);
DISPLAY INVISIBLE (4425 550);
FORCEPROP 0 LAST $SEC 1
J 0
(4575 475);
DISPLAY 0.680851 (4575 475);
PAINT MONO (4575 475);
DISPLAY INVISIBLE (4575 475);
FORCEPROP 0 LAST CDS_SEC 1
J 0
(4575 475);
DISPLAY 1.021277 (4575 475);
DISPLAY INVISIBLE (4575 475);
FORCEADD Q_RES..1
(4475 300);
FORCEPROP 1 LAST PART_NUMBER CS00002JB13
J 0
(4350 250);
DISPLAY 0.319149 (4350 250);
DISPLAY INVISIBLE (4350 250);
FORCEPROP 2 LAST ROOM HSC1_BOM2
J 0
(4275 350);
DISPLAY 1.021277 (4275 350);
FORCEPROP 1 LAST MATERIAL EMPTY
J 0
(4700 300);
DISPLAY 0.404255 (4700 300);
FORCEPROP 1 LAST TOLERANCE 5%
J 0
(4650 300);
DISPLAY 0.404255 (4650 300);
FORCEPROP 1 LAST WATTAGE 1/16W
J 2
(4600 275);
DISPLAY 0.319149 (4600 275);
FORCEPROP 1 LAST PACK_TYPE 0402LF
J 0
(4350 275);
DISPLAY 0.319149 (4350 275);
FORCEPROP 1 LAST VALUE 0
J 2
(4625 300);
DISPLAY 0.404255 (4625 300);
FORCEPROP 1 LAST LOCATION R4895
J 0
(4275 300);
DISPLAY 0.553191 (4275 300);
FORCEPROP 1 LASTPIN (4375 300) $PN 1
J 0
(4387 312);
DISPLAY 0.808511 (4387 312);
PAINT WHITE (4387 312);
FORCEPROP 1 LASTPIN (4575 300) $PN 2
J 0
(4537 312);
DISPLAY 0.808511 (4537 312);
PAINT WHITE (4537 312);
FORCEPROP 2 LAST CDS_LIB pure_quanta
J 0
(4475 300);
DISPLAY INVISIBLE (4475 300);
FORCEPROP 1 LAST PATH I16
J 0
(4425 450);
DISPLAY 0.978723 (4425 450);
PAINT WHITE (4425 450);
DISPLAY INVISIBLE (4425 450);
FORCEPROP 0 LAST $SEC 1
J 0
(4575 375);
DISPLAY 0.680851 (4575 375);
PAINT MONO (4575 375);
DISPLAY INVISIBLE (4575 375);
FORCEPROP 0 LAST CDS_SEC 1
J 0
(4575 375);
DISPLAY 1.021277 (4575 375);
DISPLAY INVISIBLE (4575 375);
FORCEADD Q_RES..2
(4800 -100);
FORCEPROP 1 LAST PART_NUMBER CS31052FB03
J 0
(4840 -225);
DISPLAY 0.638298 (4840 -225);
DISPLAY INVISIBLE (4840 -225);
FORCEPROP 2 LAST ROOM HSC1_BOM2
J 0
(4850 75);
DISPLAY 1.021277 (4850 75);
FORCEPROP 1 LAST VALUE 10.5K
J 0
(4845 -25);
DISPLAY 0.638298 (4845 -25);
FORCEPROP 1 LAST MATERIAL EMPTY
J 0
(4840 -175);
DISPLAY 0.638298 (4840 -175);
FORCEPROP 1 LAST PACK_TYPE 0402LF
J 0
(4840 -275);
DISPLAY 0.638298 (4840 -275);
FORCEPROP 1 LAST TOLERANCE 1%
J 0
(4845 -75);
DISPLAY 0.638298 (4845 -75);
FORCEPROP 1 LAST WATTAGE 1/16W
J 0
(4850 -125);
DISPLAY 0.638298 (4850 -125);
FORCEPROP 1 LAST $LOCATION R4686
J 0
(4845 25);
DISPLAY 0.787234 (4845 25);
FORCEPROP 1 LASTPIN (4800 0) $PN 1
J 0
(4805 -38);
DISPLAY 0.787234 (4805 -38);
PAINT MONO (4805 -38);
FORCEPROP 1 LASTPIN (4800 -200) $PN 2
J 0
(4805 -190);
DISPLAY 0.787234 (4805 -190);
PAINT MONO (4805 -190);
FORCEPROP 2 LAST CDS_LIB pure_quanta
J 0
(4800 -100);
DISPLAY INVISIBLE (4800 -100);
FORCEPROP 1 LAST PATH I17
J 0
(4850 75);
DISPLAY 0.978723 (4850 75);
PAINT WHITE (4850 75);
DISPLAY INVISIBLE (4850 75);
FORCEPROP 0 LAST CDS_LOCATION R4686
J 0
(4850 75);
DISPLAY 1.021277 (4850 75);
DISPLAY INVISIBLE (4850 75);
FORCEPROP 0 LAST $SEC 1
J 0
(4850 75);
DISPLAY 0.680851 (4850 75);
PAINT MONO (4850 75);
DISPLAY INVISIBLE (4850 75);
FORCEPROP 0 LAST CDS_SEC 1
J 0
(4850 75);
DISPLAY 1.021277 (4850 75);
DISPLAY INVISIBLE (4850 75);
FORCEADD UNIVERSAL_POWER..1
(4800 100);
FORCEPROP 3 LASTPIN (4800 50) SIG_NAME P3V3_AUX\g
J 0
(4810 60);
DISPLAY 0.659574 (4810 60);
PAINT MONO (4810 60);
DISPLAY INVISIBLE (4810 60);
FORCEPROP 1 LAST HDL_POWER P3V3_AUX
J 1
(4800 150);
DISPLAY 0.702128 (4800 150);
PAINT GREEN (4800 150);
FORCEPROP 1 LAST PATH I18
J 0
(4850 125);
DISPLAY 0.872340 (4850 125);
PAINT AQUA (4850 125);
DISPLAY INVISIBLE (4850 125);
FORCEPROP 2 LAST CDS_LIB logical_power
J 0
(4800 100);
DISPLAY INVISIBLE (4800 100);
FORCEADD OFFPAGE..5
R 2
(5400 -325);
FORCEPROP 2 LAST $XR0 213 
J 0
(5589 -325);
DISPLAY 0.638298 (5589 -325);
PAINT MONO (5589 -325);
FORCEPROP 2 LAST PATH I19
J 0
(5600 -275);
DISPLAY 1.021277 (5600 -275);
DISPLAY INVISIBLE (5600 -275);
FORCEPROP 1 LAST OFFPAGE TRUE
J 2
(5075 -450);
DISPLAY 0.872340 (5075 -450);
PAINT GREEN (5075 -450);
DISPLAY INVISIBLE (5075 -450);
FORCEPROP 1 LAST COMMENT_BODY TRUE
J 2
(5300 -400);
DISPLAY 0.872340 (5300 -400);
PAINT PEACH (5300 -400);
DISPLAY INVISIBLE (5300 -400);
FORCEPROP 2 LAST CDS_LIB standard
J 0
(5400 -325);
DISPLAY INVISIBLE (5400 -325);
FORCEADD OFFPAGE..4
R 2
(775 2375);
FORCEPROP 2 LAST $XR1 301 
J 0
(373 2375);
DISPLAY 0.638298 (373 2375);
PAINT MONO (373 2375);
FORCEPROP 2 LAST $XR0 241 
J 0
(493 2375);
DISPLAY 0.638298 (493 2375);
PAINT MONO (493 2375);
FORCEPROP 2 LAST PATH I2
J 0
(500 2425);
DISPLAY 1.021277 (500 2425);
DISPLAY INVISIBLE (500 2425);
FORCEPROP 2 LAST CDS_LIB standard
J 0
(775 2375);
DISPLAY INVISIBLE (775 2375);
FORCEPROP 1 LAST COMMENT_BODY TRUE
J 2
(800 2275);
DISPLAY 0.872340 (800 2275);
PAINT GREEN (800 2275);
DISPLAY INVISIBLE (800 2275);
FORCEPROP 1 LAST OFFPAGE TRUE
J 2
(450 2250);
DISPLAY 0.872340 (450 2250);
PAINT GREEN (450 2250);
DISPLAY INVISIBLE (450 2250);
FORCEADD OFFPAGE..5
R 2
(5400 200);
FORCEPROP 2 LAST $XR0 213 
J 0
(5589 200);
DISPLAY 0.638298 (5589 200);
PAINT MONO (5589 200);
FORCEPROP 2 LAST PATH I20
J 0
(5600 250);
DISPLAY 1.021277 (5600 250);
DISPLAY INVISIBLE (5600 250);
FORCEPROP 1 LAST OFFPAGE TRUE
J 2
(5075 75);
DISPLAY 0.872340 (5075 75);
PAINT GREEN (5075 75);
DISPLAY INVISIBLE (5075 75);
FORCEPROP 1 LAST COMMENT_BODY TRUE
J 2
(5300 125);
DISPLAY 0.872340 (5300 125);
PAINT PEACH (5300 125);
DISPLAY INVISIBLE (5300 125);
FORCEPROP 2 LAST CDS_LIB standard
J 2
(5400 200);
DISPLAY INVISIBLE (5400 200);
FORCEADD OFFPAGE..6
R 2
(5375 300);
FORCEPROP 2 LAST $XR2 170 
J 0
(5829 300);
DISPLAY 0.638298 (5829 300);
PAINT MONO (5829 300);
FORCEPROP 2 LAST $XR1 251 
J 0
(5709 300);
DISPLAY 0.638298 (5709 300);
PAINT MONO (5709 300);
FORCEPROP 2 LAST $XR0 233 
J 0
(5589 300);
DISPLAY 0.638298 (5589 300);
PAINT MONO (5589 300);
FORCEPROP 2 LAST PATH I21
J 0
(5850 350);
DISPLAY 1.021277 (5850 350);
DISPLAY INVISIBLE (5850 350);
FORCEPROP 1 LAST COMMENT_BODY TRUE
J 2
(5275 225);
DISPLAY 0.872340 (5275 225);
PAINT PEACH (5275 225);
DISPLAY INVISIBLE (5275 225);
FORCEPROP 1 LAST OFFPAGE TRUE
J 2
(5050 175);
DISPLAY 0.872340 (5050 175);
PAINT GREEN (5050 175);
DISPLAY INVISIBLE (5050 175);
FORCEPROP 2 LAST CDS_LIB standard
J 2
(5375 300);
DISPLAY INVISIBLE (5375 300);
FORCEADD OFFPAGE..1
R 2
(5375 400);
FORCEPROP 2 LAST $XR2 251 
J 0
(5801 400);
DISPLAY 0.638298 (5801 400);
PAINT MONO (5801 400);
FORCEPROP 2 LAST $XR1 233 
J 0
(5681 400);
DISPLAY 0.638298 (5681 400);
PAINT MONO (5681 400);
FORCEPROP 2 LAST $XR0 170 
J 0
(5561 400);
DISPLAY 0.638298 (5561 400);
PAINT MONO (5561 400);
FORCEPROP 2 LAST PATH I22
J 0
(5825 450);
DISPLAY 1.021277 (5825 450);
DISPLAY INVISIBLE (5825 450);
FORCEPROP 1 LAST OFFPAGE TRUE
J 2
(5050 275);
DISPLAY 0.872340 (5050 275);
PAINT GREEN (5050 275);
DISPLAY INVISIBLE (5050 275);
FORCEPROP 1 LAST COMMENT_BODY TRUE
J 2
(5250 300);
DISPLAY 0.872340 (5250 300);
PAINT PEACH (5250 300);
DISPLAY INVISIBLE (5250 300);
FORCEPROP 2 LAST CDS_LIB standard
J 2
(5375 400);
DISPLAY INVISIBLE (5375 400);
FORCEADD Q_RES..2
(4800 750);
FORCEPROP 1 LAST PART_NUMBER CS31052FB03
J 0
(4840 625);
DISPLAY 0.638298 (4840 625);
DISPLAY INVISIBLE (4840 625);
FORCEPROP 1 LAST WATTAGE 1/16W
J 0
(4850 725);
DISPLAY 0.638298 (4850 725);
FORCEPROP 1 LAST MATERIAL EMPTY
J 0
(4840 675);
DISPLAY 0.638298 (4840 675);
FORCEPROP 1 LAST PACK_TYPE 0402LF
J 0
(4840 575);
DISPLAY 0.638298 (4840 575);
FORCEPROP 2 LAST ROOM HSC1_BOM2
J 0
(4850 925);
DISPLAY 1.021277 (4850 925);
FORCEPROP 1 LAST TOLERANCE 1%
J 0
(4845 775);
DISPLAY 0.638298 (4845 775);
FORCEPROP 1 LAST VALUE 10.5K
J 0
(4845 825);
DISPLAY 0.638298 (4845 825);
FORCEPROP 1 LAST $LOCATION R4685
J 0
(4845 875);
DISPLAY 0.638298 (4845 875);
FORCEPROP 1 LASTPIN (4800 850) $PN 1
J 0
(4805 812);
DISPLAY 0.787234 (4805 812);
PAINT MONO (4805 812);
FORCEPROP 1 LASTPIN (4800 650) $PN 2
J 0
(4805 660);
DISPLAY 0.787234 (4805 660);
PAINT MONO (4805 660);
FORCEPROP 2 LAST CDS_LIB pure_quanta
J 0
(4800 750);
DISPLAY INVISIBLE (4800 750);
FORCEPROP 1 LAST PATH I23
J 0
(4850 925);
DISPLAY 0.978723 (4850 925);
PAINT WHITE (4850 925);
DISPLAY INVISIBLE (4850 925);
FORCEPROP 0 LAST CDS_LOCATION R4685
J 0
(4850 925);
DISPLAY 1.021277 (4850 925);
DISPLAY INVISIBLE (4850 925);
FORCEPROP 0 LAST $SEC 1
J 0
(4850 925);
DISPLAY 0.680851 (4850 925);
PAINT MONO (4850 925);
DISPLAY INVISIBLE (4850 925);
FORCEPROP 0 LAST CDS_SEC 1
J 0
(4850 925);
DISPLAY 1.021277 (4850 925);
DISPLAY INVISIBLE (4850 925);
FORCEADD UNIVERSAL_POWER..1
(4800 975);
FORCEPROP 3 LASTPIN (4800 925) SIG_NAME P3V3_AUX\g
J 0
(4810 935);
DISPLAY 0.659574 (4810 935);
PAINT MONO (4810 935);
DISPLAY INVISIBLE (4810 935);
FORCEPROP 1 LAST HDL_POWER P3V3_AUX
J 1
(4800 1025);
DISPLAY 0.702128 (4800 1025);
PAINT GREEN (4800 1025);
FORCEPROP 1 LAST PATH I24
J 0
(4850 1000);
DISPLAY 0.872340 (4850 1000);
PAINT AQUA (4850 1000);
DISPLAY INVISIBLE (4850 1000);
FORCEPROP 2 LAST CDS_LIB logical_power
J 0
(4800 975);
DISPLAY INVISIBLE (4800 975);
FORCEADD Q_RES..1
(1925 2325);
FORCEPROP 1 LAST PART_NUMBER CS00002JB13
J 0
(1600 2275);
DISPLAY 0.723404 (1600 2275);
PAINT WHITE (1600 2275);
DISPLAY INVISIBLE (1600 2275);
FORCEPROP 1 LAST MATERIAL CHIP
J 0
(2100 2325);
DISPLAY 0.723404 (2100 2325);
FORCEPROP 1 LAST VALUE 0
J 2
(2075 2325);
DISPLAY 0.723404 (2075 2325);
FORCEPROP 1 LAST $LOCATION R4696
J 0
(1650 2325);
DISPLAY 0.723404 (1650 2325);
FORCEPROP 1 LASTPIN (1825 2325) $PN 1
J 0
(1837 2337);
DISPLAY 0.787234 (1837 2337);
PAINT MONO (1837 2337);
FORCEPROP 1 LASTPIN (2025 2325) $PN 2
J 0
(1987 2337);
DISPLAY 0.787234 (1987 2337);
PAINT MONO (1987 2337);
FORCEPROP 1 LAST PATH I25
J 0
(1875 2475);
DISPLAY 0.978723 (1875 2475);
PAINT WHITE (1875 2475);
DISPLAY INVISIBLE (1875 2475);
FORCEPROP 1 LAST PACK_TYPE 0402LF
J 0
(2125 2275);
DISPLAY 0.723404 (2125 2275);
PAINT SKYBLUE (2125 2275);
DISPLAY INVISIBLE (2125 2275);
FORCEPROP 1 LAST WATTAGE 1/16W
J 2
(2325 2325);
DISPLAY 0.723404 (2325 2325);
PAINT SKYBLUE (2325 2325);
DISPLAY INVISIBLE (2325 2325);
FORCEPROP 1 LAST TOLERANCE 5%
J 0
(2000 2275);
DISPLAY 0.723404 (2000 2275);
PAINT SKYBLUE (2000 2275);
DISPLAY INVISIBLE (2000 2275);
FORCEPROP 2 LAST CDS_LIB pure_quanta
J 0
(1925 2325);
DISPLAY INVISIBLE (1925 2325);
FORCEPROP 0 LAST CDS_LOCATION R4696
J 0
(2100 2375);
DISPLAY 1.021277 (2100 2375);
DISPLAY INVISIBLE (2100 2375);
FORCEPROP 0 LAST $SEC 1
J 0
(2100 2375);
DISPLAY 0.680851 (2100 2375);
PAINT MONO (2100 2375);
DISPLAY INVISIBLE (2100 2375);
FORCEPROP 0 LAST CDS_SEC 1
J 0
(2100 2375);
DISPLAY 1.021277 (2100 2375);
DISPLAY INVISIBLE (2100 2375);
FORCEADD Q_RES..1
(1925 2375);
FORCEPROP 1 LAST PART_NUMBER CS00002JB13
J 0
(1600 2325);
DISPLAY 0.723404 (1600 2325);
PAINT WHITE (1600 2325);
DISPLAY INVISIBLE (1600 2325);
FORCEPROP 1 LAST MATERIAL CHIP
J 0
(2100 2375);
DISPLAY 0.723404 (2100 2375);
FORCEPROP 1 LAST VALUE 0
J 2
(2075 2375);
DISPLAY 0.723404 (2075 2375);
FORCEPROP 1 LAST $LOCATION R4695
J 0
(1650 2375);
DISPLAY 0.723404 (1650 2375);
FORCEPROP 1 LASTPIN (1825 2375) $PN 1
J 0
(1837 2387);
DISPLAY 0.787234 (1837 2387);
PAINT MONO (1837 2387);
FORCEPROP 1 LASTPIN (2025 2375) $PN 2
J 0
(1987 2387);
DISPLAY 0.787234 (1987 2387);
PAINT MONO (1987 2387);
FORCEPROP 1 LAST PATH I26
J 0
(1875 2525);
DISPLAY 0.978723 (1875 2525);
PAINT WHITE (1875 2525);
DISPLAY INVISIBLE (1875 2525);
FORCEPROP 1 LAST PACK_TYPE 0402LF
J 0
(2125 2325);
DISPLAY 0.723404 (2125 2325);
PAINT SKYBLUE (2125 2325);
DISPLAY INVISIBLE (2125 2325);
FORCEPROP 1 LAST WATTAGE 1/16W
J 2
(2325 2375);
DISPLAY 0.723404 (2325 2375);
PAINT SKYBLUE (2325 2375);
DISPLAY INVISIBLE (2325 2375);
FORCEPROP 1 LAST TOLERANCE 5%
J 0
(2000 2325);
DISPLAY 0.723404 (2000 2325);
PAINT SKYBLUE (2000 2325);
DISPLAY INVISIBLE (2000 2325);
FORCEPROP 2 LAST CDS_LIB pure_quanta
J 0
(1925 2375);
DISPLAY INVISIBLE (1925 2375);
FORCEPROP 0 LAST CDS_LOCATION R4695
J 0
(2100 2425);
DISPLAY 1.021277 (2100 2425);
DISPLAY INVISIBLE (2100 2425);
FORCEPROP 0 LAST $SEC 1
J 0
(2100 2425);
DISPLAY 0.680851 (2100 2425);
PAINT MONO (2100 2425);
DISPLAY INVISIBLE (2100 2425);
FORCEPROP 0 LAST CDS_SEC 1
J 0
(2100 2425);
DISPLAY 1.021277 (2100 2425);
DISPLAY INVISIBLE (2100 2425);
FORCEADD OFFPAGE..5
(2425 2275);
FORCEPROP 2 LAST $XR3 215 
J 0
(2020 2239);
DISPLAY 0.638298 (2020 2239);
PAINT MONO (2020 2239);
FORCEPROP 2 LAST $XR2 183 
J 0
(2140 2239);
DISPLAY 0.638298 (2140 2239);
PAINT MONO (2140 2239);
FORCEPROP 2 LAST $XR1 301 
J 0
(2020 2275);
DISPLAY 0.638298 (2020 2275);
PAINT MONO (2020 2275);
FORCEPROP 2 LAST $XR0 228 
J 0
(2140 2275);
DISPLAY 0.638298 (2140 2275);
PAINT MONO (2140 2275);
FORCEPROP 2 LAST PATH I27
J 0
(2150 2325);
DISPLAY 1.021277 (2150 2325);
DISPLAY INVISIBLE (2150 2325);
FORCEPROP 2 LAST CDS_LIB standard
J 2
(2425 2275);
DISPLAY INVISIBLE (2425 2275);
FORCEPROP 1 LAST OFFPAGE TRUE
J 0
(2750 2150);
DISPLAY 0.872340 (2750 2150);
PAINT AQUA (2750 2150);
DISPLAY INVISIBLE (2750 2150);
FORCEPROP 1 LAST COMMENT_BODY TRUE
J 0
(2525 2200);
DISPLAY 1.170213 (2525 2200);
PAINT GREEN (2525 2200);
DISPLAY INVISIBLE (2525 2200);
FORCEADD OFFPAGE..5
(2425 2425);
FORCEPROP 2 LAST $XR0 251 
J 0
(2140 2425);
DISPLAY 0.638298 (2140 2425);
PAINT MONO (2140 2425);
FORCEPROP 2 LAST PATH I28
J 0
(2150 2475);
DISPLAY 1.021277 (2150 2475);
DISPLAY INVISIBLE (2150 2475);
FORCEPROP 2 LAST CDS_LIB standard
J 0
(2425 2425);
DISPLAY INVISIBLE (2425 2425);
FORCEPROP 1 LAST COMMENT_BODY TRUE
J 0
(2525 2350);
DISPLAY 1.170213 (2525 2350);
PAINT GREEN (2525 2350);
DISPLAY INVISIBLE (2525 2350);
FORCEPROP 1 LAST OFFPAGE TRUE
J 0
(2750 2300);
DISPLAY 0.872340 (2750 2300);
PAINT AQUA (2750 2300);
DISPLAY INVISIBLE (2750 2300);
FORCEADD OFFPAGE..5
(2425 2475);
FORCEPROP 2 LAST $XR0 306 
J 0
(2140 2475);
DISPLAY 0.638298 (2140 2475);
PAINT MONO (2140 2475);
FORCEPROP 2 LAST PATH I29
J 0
(2150 2525);
DISPLAY 1.021277 (2150 2525);
DISPLAY INVISIBLE (2150 2525);
FORCEPROP 2 LAST CDS_LIB standard
J 0
(2425 2475);
DISPLAY INVISIBLE (2425 2475);
FORCEPROP 1 LAST OFFPAGE TRUE
J 0
(2750 2350);
DISPLAY 0.872340 (2750 2350);
PAINT AQUA (2750 2350);
DISPLAY INVISIBLE (2750 2350);
FORCEPROP 1 LAST COMMENT_BODY TRUE
J 0
(2525 2400);
DISPLAY 1.170213 (2525 2400);
PAINT GREEN (2525 2400);
DISPLAY INVISIBLE (2525 2400);
FORCEADD OFFPAGE..3
R 2
(775 2325);
FORCEPROP 2 LAST $XR1 301 
J 0
(345 2325);
DISPLAY 0.638298 (345 2325);
PAINT MONO (345 2325);
FORCEPROP 2 LAST $XR0 241 
J 0
(465 2325);
DISPLAY 0.638298 (465 2325);
PAINT MONO (465 2325);
FORCEPROP 2 LAST PATH I3
J 0
(475 2375);
DISPLAY 1.021277 (475 2375);
DISPLAY INVISIBLE (475 2375);
FORCEPROP 1 LAST COMMENT_BODY TRUE
J 2
(825 2225);
DISPLAY 0.872340 (825 2225);
PAINT GREEN (825 2225);
DISPLAY INVISIBLE (825 2225);
FORCEPROP 1 LAST OFFPAGE TRUE
J 2
(450 2200);
DISPLAY 0.872340 (450 2200);
PAINT GREEN (450 2200);
DISPLAY INVISIBLE (450 2200);
FORCEPROP 2 LAST CDS_LIB standard
J 2
(775 2325);
DISPLAY INVISIBLE (775 2325);
FORCEADD OFFPAGE..5
(2425 2525);
FORCEPROP 2 LAST $XR3 259 
J 0
(1780 2525);
DISPLAY 0.638298 (1780 2525);
PAINT MONO (1780 2525);
FORCEPROP 2 LAST $XR2 247 
J 0
(1900 2525);
DISPLAY 0.638298 (1900 2525);
PAINT MONO (1900 2525);
FORCEPROP 2 LAST $XR1 214 
J 0
(2020 2525);
DISPLAY 0.638298 (2020 2525);
PAINT MONO (2020 2525);
FORCEPROP 2 LAST $XR0 301 
J 0
(2140 2525);
DISPLAY 0.638298 (2140 2525);
PAINT MONO (2140 2525);
FORCEPROP 2 LAST PATH I30
J 0
(2150 2575);
DISPLAY 1.021277 (2150 2575);
DISPLAY INVISIBLE (2150 2575);
FORCEPROP 1 LAST COMMENT_BODY TRUE
J 0
(2525 2450);
DISPLAY 1.170213 (2525 2450);
PAINT GREEN (2525 2450);
DISPLAY INVISIBLE (2525 2450);
FORCEPROP 1 LAST OFFPAGE TRUE
J 0
(2750 2400);
DISPLAY 0.872340 (2750 2400);
PAINT AQUA (2750 2400);
DISPLAY INVISIBLE (2750 2400);
FORCEPROP 2 LAST CDS_LIB standard
J 0
(2425 2525);
DISPLAY INVISIBLE (2425 2525);
FORCEADD OFFPAGE..4
R 2
(2425 2575);
FORCEPROP 2 LAST $XR0 301 
J 0
(2143 2575);
DISPLAY 0.638298 (2143 2575);
PAINT MONO (2143 2575);
FORCEPROP 2 LAST PATH I31
J 0
(2150 2625);
DISPLAY 1.021277 (2150 2625);
DISPLAY INVISIBLE (2150 2625);
FORCEPROP 1 LAST OFFPAGE TRUE
J 2
(2100 2450);
DISPLAY 0.872340 (2100 2450);
PAINT GREEN (2100 2450);
DISPLAY INVISIBLE (2100 2450);
FORCEPROP 1 LAST COMMENT_BODY TRUE
J 2
(2450 2475);
DISPLAY 0.872340 (2450 2475);
PAINT GREEN (2450 2475);
DISPLAY INVISIBLE (2450 2475);
FORCEPROP 2 LAST CDS_LIB standard
J 0
(2425 2575);
DISPLAY INVISIBLE (2425 2575);
FORCEADD OFFPAGE..5
(2425 2625);
FORCEPROP 2 LAST $XR1 213 
J 0
(2020 2625);
DISPLAY 0.638298 (2020 2625);
PAINT MONO (2020 2625);
FORCEPROP 2 LAST $XR0 301 
J 0
(2140 2625);
DISPLAY 0.638298 (2140 2625);
PAINT MONO (2140 2625);
FORCEPROP 2 LAST PATH I32
J 0
(2150 2675);
DISPLAY 1.021277 (2150 2675);
DISPLAY INVISIBLE (2150 2675);
FORCEPROP 2 LAST CDS_LIB standard
J 0
(2425 2625);
DISPLAY INVISIBLE (2425 2625);
FORCEPROP 1 LAST OFFPAGE TRUE
J 0
(2750 2500);
DISPLAY 0.872340 (2750 2500);
PAINT AQUA (2750 2500);
DISPLAY INVISIBLE (2750 2500);
FORCEPROP 1 LAST COMMENT_BODY TRUE
J 0
(2525 2550);
DISPLAY 1.170213 (2525 2550);
PAINT GREEN (2525 2550);
DISPLAY INVISIBLE (2525 2550);
FORCEADD UNIVERSAL_GND..1
(3200 1850);
FORCEPROP 3 LASTPIN (3200 1900) SIG_NAME GND\g
J 0
(3210 1910);
DISPLAY 0.659574 (3210 1910);
PAINT MONO (3210 1910);
DISPLAY INVISIBLE (3210 1910);
FORCEPROP 1 LAST HDL_POWER GND
J 1
(3225 1775);
DISPLAY 0.872340 (3225 1775);
PAINT GREEN (3225 1775);
DISPLAY INVISIBLE (3225 1775);
FORCEPROP 1 LAST PATH I33
J 0
(3275 1850);
DISPLAY 0.872340 (3275 1850);
PAINT AQUA (3275 1850);
DISPLAY INVISIBLE (3275 1850);
FORCEPROP 2 LAST CDS_LIB logical_power
J 0
(3200 1850);
DISPLAY INVISIBLE (3200 1850);
FORCEADD SCONN21_9193031121LF..1
R 2
(3650 2350);
FORCEPROP 1 LAST PART_NUMBER DFHS21FS003
J 0
(3475 2834);
DISPLAY 0.723404 (3475 2834);
PAINT GREEN (3475 2834);
DISPLAY INVISIBLE (3475 2834);
FORCEPROP 2 LAST VALUE SCONN21_91930-31121LF
J 0
(3475 2919);
DISPLAY 1.021277 (3475 2919);
FORCEPROP 2 LAST ROOM HSC1_BOM2
J 0
(3475 3025);
DISPLAY 1.021277 (3475 3025);
FORCEPROP 1 LAST MATERIAL EMPTY
J 2
(3794 2782);
DISPLAY 0.723404 (3794 2782);
PAINT GREEN (3794 2782);
FORCEPROP 2 LAST PART_TYPE SMLF
J 0
(3475 2969);
DISPLAY 1.021277 (3475 2969);
FORCEPROP 1 LAST LOCATION PJ42
J 0
(3475 2875);
DISPLAY 0.723404 (3475 2875);
PAINT GREEN (3475 2875);
FORCEPROP 0 LASTPIN (3950 2675) $PN 1
J 0
(3960 2685);
DISPLAY 0.680851 (3960 2685);
PAINT MONO (3960 2685);
FORCEPROP 0 LASTPIN (3950 2625) $PN 2
J 0
(3960 2635);
DISPLAY 0.680851 (3960 2635);
PAINT MONO (3960 2635);
FORCEPROP 0 LASTPIN (3950 2575) $PN 3
J 0
(3960 2585);
DISPLAY 0.680851 (3960 2585);
PAINT MONO (3960 2585);
FORCEPROP 0 LASTPIN (3950 2525) $PN 4
J 0
(3960 2535);
DISPLAY 0.680851 (3960 2535);
PAINT MONO (3960 2535);
FORCEPROP 0 LASTPIN (3950 2475) $PN 5
J 0
(3960 2485);
DISPLAY 0.680851 (3960 2485);
PAINT MONO (3960 2485);
FORCEPROP 0 LASTPIN (3950 2425) $PN 6
J 0
(3960 2435);
DISPLAY 0.680851 (3960 2435);
PAINT MONO (3960 2435);
FORCEPROP 0 LASTPIN (3950 2375) $PN 7
J 0
(3960 2385);
DISPLAY 0.680851 (3960 2385);
PAINT MONO (3960 2385);
FORCEPROP 0 LASTPIN (3950 2325) $PN 8
J 0
(3960 2335);
DISPLAY 0.680851 (3960 2335);
PAINT MONO (3960 2335);
FORCEPROP 0 LASTPIN (3950 2275) $PN 9
J 0
(3960 2285);
DISPLAY 0.680851 (3960 2285);
PAINT MONO (3960 2285);
FORCEPROP 0 LASTPIN (3950 2225) $PN 10
J 0
(3960 2235);
DISPLAY 0.680851 (3960 2235);
PAINT MONO (3960 2235);
FORCEPROP 0 LASTPIN (3950 2175) $PN 11
J 0
(3960 2185);
DISPLAY 0.680851 (3960 2185);
PAINT MONO (3960 2185);
FORCEPROP 0 LASTPIN (3350 2675) $PN 12
J 2
(3340 2685);
DISPLAY 0.680851 (3340 2685);
PAINT MONO (3340 2685);
FORCEPROP 0 LASTPIN (3350 2625) $PN 13
J 2
(3340 2635);
DISPLAY 0.680851 (3340 2635);
PAINT MONO (3340 2635);
FORCEPROP 0 LASTPIN (3350 2575) $PN 14
J 2
(3340 2585);
DISPLAY 0.680851 (3340 2585);
PAINT MONO (3340 2585);
FORCEPROP 0 LASTPIN (3350 2525) $PN 15
J 2
(3340 2535);
DISPLAY 0.680851 (3340 2535);
PAINT MONO (3340 2535);
FORCEPROP 0 LASTPIN (3350 2475) $PN 16
J 2
(3340 2485);
DISPLAY 0.680851 (3340 2485);
PAINT MONO (3340 2485);
FORCEPROP 0 LASTPIN (3350 2425) $PN 17
J 2
(3340 2435);
DISPLAY 0.680851 (3340 2435);
PAINT MONO (3340 2435);
FORCEPROP 0 LASTPIN (3350 2375) $PN 18
J 2
(3340 2385);
DISPLAY 0.680851 (3340 2385);
PAINT MONO (3340 2385);
FORCEPROP 0 LASTPIN (3350 2325) $PN 19
J 2
(3340 2335);
DISPLAY 0.680851 (3340 2335);
PAINT MONO (3340 2335);
FORCEPROP 0 LASTPIN (3350 2275) $PN 20
J 2
(3340 2285);
DISPLAY 0.680851 (3340 2285);
PAINT MONO (3340 2285);
FORCEPROP 0 LASTPIN (3350 2225) $PN 21
J 2
(3340 2235);
DISPLAY 0.680851 (3340 2235);
PAINT MONO (3340 2235);
FORCEPROP 0 LASTPIN (3350 2075) $PN G1
J 2
(3340 2085);
DISPLAY 0.680851 (3340 2085);
PAINT MONO (3340 2085);
FORCEPROP 0 LASTPIN (3350 2025) $PN G2
J 2
(3340 2035);
DISPLAY 0.680851 (3340 2035);
PAINT MONO (3340 2035);
FORCEPROP 1 LAST NEEDS_NO_SIZE TRUE
J 2
(3650 2350);
DISPLAY 0.723404 (3650 2350);
PAINT GREEN (3650 2350);
DISPLAY INVISIBLE (3650 2350);
FORCEPROP 1 LAST CDS_LMAN_SYM_OUTLINE -150,425,150,-425
J 2
(3650 2350);
DISPLAY 0.468085 (3650 2350);
PAINT GREEN (3650 2350);
DISPLAY INVISIBLE (3650 2350);
FORCEPROP 2 LAST CDS_LIB pure_quanta
J 0
(3650 2350);
DISPLAY INVISIBLE (3650 2350);
FORCEPROP 1 LAST PATH I34
J 2
(3650 2350);
DISPLAY 0.723404 (3650 2350);
PAINT GREEN (3650 2350);
DISPLAY INVISIBLE (3650 2350);
FORCEPROP 0 LAST $SEC 1
J 0
(3475 3025);
DISPLAY 0.680851 (3475 3025);
PAINT MONO (3475 3025);
DISPLAY INVISIBLE (3475 3025);
FORCEPROP 0 LAST CDS_SEC 1
J 0
(3475 3025);
DISPLAY 1.021277 (3475 3025);
DISPLAY INVISIBLE (3475 3025);
FORCEADD UNIVERSAL_POWER..1
(2950 2775);
FORCEPROP 3 LASTPIN (2950 2725) SIG_NAME P3V3_AUX\g
J 0
(2960 2735);
DISPLAY 0.659574 (2960 2735);
PAINT MONO (2960 2735);
DISPLAY INVISIBLE (2960 2735);
FORCEPROP 1 LAST HDL_POWER P3V3_AUX
J 1
(2950 2825);
DISPLAY 0.723404 (2950 2825);
PAINT GREEN (2950 2825);
FORCEPROP 1 LAST PATH I35
J 0
(3000 2800);
DISPLAY 0.872340 (3000 2800);
PAINT AQUA (3000 2800);
DISPLAY INVISIBLE (3000 2800);
FORCEPROP 2 LAST CDS_LIB logical_power
J 0
(2950 2775);
DISPLAY INVISIBLE (2950 2775);
FORCEADD UNIVERSAL_GND..1
(4050 2000);
FORCEPROP 3 LASTPIN (4050 2050) SIG_NAME GND\g
J 0
(4060 2060);
DISPLAY 0.659574 (4060 2060);
PAINT MONO (4060 2060);
DISPLAY INVISIBLE (4060 2060);
FORCEPROP 1 LAST PATH I36
J 0
(4125 2000);
DISPLAY 0.872340 (4125 2000);
PAINT AQUA (4125 2000);
DISPLAY INVISIBLE (4125 2000);
FORCEPROP 1 LAST HDL_POWER GND
J 1
(4075 1925);
DISPLAY 0.872340 (4075 1925);
PAINT GREEN (4075 1925);
DISPLAY INVISIBLE (4075 1925);
FORCEPROP 2 LAST CDS_LIB logical_power
J 0
(4050 2000);
DISPLAY INVISIBLE (4050 2000);
FORCEADD UNIVERSAL_GND..1
(4425 1775);
FORCEPROP 3 LASTPIN (4425 1825) SIG_NAME GND\g
J 0
(4435 1835);
DISPLAY 0.659574 (4435 1835);
PAINT MONO (4435 1835);
DISPLAY INVISIBLE (4435 1835);
FORCEPROP 1 LAST PATH I37
J 0
(4500 1775);
DISPLAY 0.872340 (4500 1775);
PAINT AQUA (4500 1775);
DISPLAY INVISIBLE (4500 1775);
FORCEPROP 1 LAST HDL_POWER GND
J 1
(4450 1700);
DISPLAY 0.872340 (4450 1700);
PAINT GREEN (4450 1700);
DISPLAY INVISIBLE (4450 1700);
FORCEPROP 2 LAST CDS_LIB logical_power
J 0
(4425 1775);
DISPLAY INVISIBLE (4425 1775);
FORCEADD Q_CAP..1
(4425 1950);
FORCEPROP 1 LAST PART_NUMBER CH4104K1B00
J 0
(4500 2000);
DISPLAY 0.723404 (4500 2000);
PAINT BLUE (4500 2000);
DISPLAY INVISIBLE (4500 2000);
FORCEPROP 2 LAST ROOM HSC1_BOM2
J 0
(4500 2100);
DISPLAY 1.021277 (4500 2100);
FORCEPROP 1 LAST VALUE 0.1UF
J 0
(4500 1950);
DISPLAY 0.723404 (4500 1950);
PAINT SKYBLUE (4500 1950);
FORCEPROP 1 LAST VOLTAGE 25V
J 0
(4500 1900);
DISPLAY 0.723404 (4500 1900);
PAINT SKYBLUE (4500 1900);
FORCEPROP 1 LAST TOLERANCE 10%
J 0
(4500 1850);
DISPLAY 0.723404 (4500 1850);
PAINT SKYBLUE (4500 1850);
FORCEPROP 1 LAST MATERIAL EMPTY
J 0
(4500 1800);
DISPLAY 0.723404 (4500 1800);
PAINT SKYBLUE (4500 1800);
FORCEPROP 1 LAST PACK_TYPE 0402
J 0
(4500 1750);
DISPLAY 0.723404 (4500 1750);
PAINT SKYBLUE (4500 1750);
FORCEPROP 1 LAST $LOCATION PC1789
J 0
(4500 2050);
DISPLAY 0.978723 (4500 2050);
FORCEPROP 1 LASTPIN (4425 2050) $PN 1
J 0
(4435 2030);
DISPLAY 0.787234 (4435 2030);
PAINT MONO (4435 2030);
FORCEPROP 1 LASTPIN (4425 1850) $PN 2
J 0
(4435 1830);
DISPLAY 0.787234 (4435 1830);
PAINT MONO (4435 1830);
FORCEPROP 2 LAST CDS_LIB pure_quanta
J 0
(4425 1950);
DISPLAY INVISIBLE (4425 1950);
FORCEPROP 1 LAST PATH I38
J 0
(4475 2100);
DISPLAY 0.978723 (4475 2100);
PAINT WHITE (4475 2100);
DISPLAY INVISIBLE (4475 2100);
FORCEPROP 0 LAST CDS_LOCATION PC1789
J 0
(4500 2100);
DISPLAY 1.021277 (4500 2100);
DISPLAY INVISIBLE (4500 2100);
FORCEPROP 0 LAST $SEC 1
J 0
(4500 2100);
DISPLAY 0.680851 (4500 2100);
PAINT MONO (4500 2100);
DISPLAY INVISIBLE (4500 2100);
FORCEPROP 0 LAST CDS_SEC 1
J 0
(4500 2100);
DISPLAY 1.021277 (4500 2100);
DISPLAY INVISIBLE (4500 2100);
FORCEADD OFFPAGE..2
(4650 2275);
FORCEPROP 2 LAST $XR0 304 
J 0
(4839 2275);
DISPLAY 0.638298 (4839 2275);
PAINT MONO (4839 2275);
FORCEPROP 1 LAST OFFPAGE TRUE
J 0
(4975 2150);
DISPLAY 0.872340 (4975 2150);
PAINT AQUA (4975 2150);
DISPLAY INVISIBLE (4975 2150);
FORCEPROP 1 LAST COMMENT_BODY TRUE
J 0
(4605 2180);
DISPLAY 0.872340 (4605 2180);
PAINT GREEN (4605 2180);
DISPLAY INVISIBLE (4605 2180);
FORCEPROP 2 LAST PATH I39
J 0
(4850 2325);
DISPLAY 1.021277 (4850 2325);
DISPLAY INVISIBLE (4850 2325);
FORCEPROP 2 LAST CDS_LIB standard
J 0
(4650 2275);
DISPLAY INVISIBLE (4650 2275);
FORCEADD Q_RES..1
(1725 -50);
FORCEPROP 1 LAST PART_NUMBER CS04992FB07
J 0
(1550 -200);
DISPLAY 0.638298 (1550 -200);
DISPLAY INVISIBLE (1550 -200);
FORCEPROP 2 LAST ROOM HSC1_BOM2
J 0
(1575 50);
DISPLAY 1.021277 (1575 50);
FORCEPROP 1 LAST WATTAGE 1/16W
J 2
(1700 -100);
DISPLAY 0.638298 (1700 -100);
FORCEPROP 1 LAST MATERIAL EMPTY
J 0
(1800 -150);
DISPLAY 0.638298 (1800 -150);
FORCEPROP 1 LAST PACK_TYPE 0402LF
J 0
(1550 -150);
DISPLAY 0.638298 (1550 -150);
FORCEPROP 1 LAST TOLERANCE 1%
J 0
(1800 -100);
DISPLAY 0.638298 (1800 -100);
FORCEPROP 1 LAST VALUE 49.9
J 2
(1975 -25);
DISPLAY 0.638298 (1975 -25);
FORCEPROP 1 LAST LOCATION R4893
J 0
(1575 0);
DISPLAY 0.638298 (1575 0);
FORCEPROP 1 LASTPIN (1625 -50) $PN 1
J 0
(1637 -38);
DISPLAY 0.787234 (1637 -38);
PAINT MONO (1637 -38);
FORCEPROP 1 LASTPIN (1825 -50) $PN 2
J 0
(1787 -38);
DISPLAY 0.787234 (1787 -38);
PAINT MONO (1787 -38);
FORCEPROP 2 LAST CDS_LIB pure_quanta
J 0
(1725 -50);
DISPLAY INVISIBLE (1725 -50);
FORCEPROP 1 LAST PATH I4
J 0
(1675 100);
DISPLAY 0.978723 (1675 100);
PAINT WHITE (1675 100);
DISPLAY INVISIBLE (1675 100);
FORCEPROP 0 LAST $SEC 1
J 0
(1900 25);
DISPLAY 0.680851 (1900 25);
PAINT MONO (1900 25);
DISPLAY INVISIBLE (1900 25);
FORCEPROP 0 LAST CDS_SEC 1
J 0
(1775 125);
DISPLAY 1.021277 (1775 125);
DISPLAY INVISIBLE (1775 125);
FORCEADD OFFPAGE..4
(4650 2375);
FORCEPROP 2 LAST $XR0 304 
J 0
(4836 2375);
DISPLAY 0.638298 (4836 2375);
PAINT MONO (4836 2375);
FORCEPROP 2 LAST PATH I40
J 0
(4850 2425);
DISPLAY 1.021277 (4850 2425);
DISPLAY INVISIBLE (4850 2425);
FORCEPROP 1 LAST COMMENT_BODY TRUE
J 0
(4625 2275);
DISPLAY 0.872340 (4625 2275);
PAINT GREEN (4625 2275);
DISPLAY INVISIBLE (4625 2275);
FORCEPROP 1 LAST OFFPAGE TRUE
J 0
(4975 2250);
DISPLAY 0.872340 (4975 2250);
PAINT GREEN (4975 2250);
DISPLAY INVISIBLE (4975 2250);
FORCEPROP 2 LAST CDS_LIB standard
J 0
(4650 2375);
DISPLAY INVISIBLE (4650 2375);
FORCEADD OFFPAGE..2
(4650 2325);
FORCEPROP 2 LAST $XR0 304 
J 0
(4839 2325);
DISPLAY 0.638298 (4839 2325);
PAINT MONO (4839 2325);
FORCEPROP 2 LAST PATH I41
J 0
(4850 2375);
DISPLAY 1.021277 (4850 2375);
DISPLAY INVISIBLE (4850 2375);
FORCEPROP 1 LAST COMMENT_BODY TRUE
J 0
(4605 2230);
DISPLAY 0.872340 (4605 2230);
PAINT GREEN (4605 2230);
DISPLAY INVISIBLE (4605 2230);
FORCEPROP 1 LAST OFFPAGE TRUE
J 0
(4975 2200);
DISPLAY 0.872340 (4975 2200);
PAINT AQUA (4975 2200);
DISPLAY INVISIBLE (4975 2200);
FORCEPROP 2 LAST CDS_LIB standard
J 0
(4650 2325);
DISPLAY INVISIBLE (4650 2325);
FORCEADD OFFPAGE..4
(4650 2425);
FORCEPROP 2 LAST $XR0 304 
J 0
(4836 2425);
DISPLAY 0.638298 (4836 2425);
PAINT MONO (4836 2425);
FORCEPROP 2 LAST PATH I42
J 0
(4850 2475);
DISPLAY 1.021277 (4850 2475);
DISPLAY INVISIBLE (4850 2475);
FORCEPROP 1 LAST COMMENT_BODY TRUE
J 0
(4625 2325);
DISPLAY 0.872340 (4625 2325);
PAINT GREEN (4625 2325);
DISPLAY INVISIBLE (4625 2325);
FORCEPROP 1 LAST OFFPAGE TRUE
J 0
(4975 2300);
DISPLAY 0.872340 (4975 2300);
PAINT GREEN (4975 2300);
DISPLAY INVISIBLE (4975 2300);
FORCEPROP 2 LAST CDS_LIB standard
J 0
(4650 2425);
DISPLAY INVISIBLE (4650 2425);
FORCEADD OFFPAGE..4
(4650 2525);
FORCEPROP 2 LAST $XR0 304 
J 0
(4836 2525);
DISPLAY 0.638298 (4836 2525);
PAINT MONO (4836 2525);
FORCEPROP 2 LAST PATH I43
J 0
(4850 2575);
DISPLAY 1.021277 (4850 2575);
DISPLAY INVISIBLE (4850 2575);
FORCEPROP 1 LAST COMMENT_BODY TRUE
J 0
(4625 2425);
DISPLAY 0.872340 (4625 2425);
PAINT GREEN (4625 2425);
DISPLAY INVISIBLE (4625 2425);
FORCEPROP 1 LAST OFFPAGE TRUE
J 0
(4975 2400);
DISPLAY 0.872340 (4975 2400);
PAINT GREEN (4975 2400);
DISPLAY INVISIBLE (4975 2400);
FORCEPROP 2 LAST CDS_LIB standard
J 0
(4650 2525);
DISPLAY INVISIBLE (4650 2525);
FORCEADD OFFPAGE..4
(4650 2475);
FORCEPROP 2 LAST $XR0 304 
J 0
(4836 2475);
DISPLAY 0.638298 (4836 2475);
PAINT MONO (4836 2475);
FORCEPROP 2 LAST PATH I44
J 0
(4850 2525);
DISPLAY 1.021277 (4850 2525);
DISPLAY INVISIBLE (4850 2525);
FORCEPROP 1 LAST COMMENT_BODY TRUE
J 0
(4625 2375);
DISPLAY 0.872340 (4625 2375);
PAINT GREEN (4625 2375);
DISPLAY INVISIBLE (4625 2375);
FORCEPROP 1 LAST OFFPAGE TRUE
J 0
(4975 2350);
DISPLAY 0.872340 (4975 2350);
PAINT GREEN (4975 2350);
DISPLAY INVISIBLE (4975 2350);
FORCEPROP 2 LAST CDS_LIB standard
J 0
(4650 2475);
DISPLAY INVISIBLE (4650 2475);
FORCEADD OFFPAGE..4
(4650 2575);
FORCEPROP 2 LAST $XR0 304 
J 0
(4836 2575);
DISPLAY 0.638298 (4836 2575);
PAINT MONO (4836 2575);
FORCEPROP 2 LAST PATH I45
J 0
(4850 2625);
DISPLAY 1.021277 (4850 2625);
DISPLAY INVISIBLE (4850 2625);
FORCEPROP 1 LAST COMMENT_BODY TRUE
J 0
(4625 2475);
DISPLAY 0.872340 (4625 2475);
PAINT GREEN (4625 2475);
DISPLAY INVISIBLE (4625 2475);
FORCEPROP 1 LAST OFFPAGE TRUE
J 0
(4975 2450);
DISPLAY 0.872340 (4975 2450);
PAINT GREEN (4975 2450);
DISPLAY INVISIBLE (4975 2450);
FORCEPROP 2 LAST CDS_LIB standard
J 0
(4650 2575);
DISPLAY INVISIBLE (4650 2575);
FORCEADD UNIVERSAL_POWER..1
(5175 2275);
FORCEPROP 1 LAST HDL_POWER P12V_AUX
J 1
(5175 2325);
DISPLAY 0.702128 (5175 2325);
PAINT GREEN (5175 2325);
FORCEPROP 1 LAST PATH I46
J 0
(5225 2300);
DISPLAY 0.872340 (5225 2300);
PAINT AQUA (5225 2300);
DISPLAY INVISIBLE (5225 2300);
FORCEPROP 2 LAST CDS_LIB logical_power
J 0
(5175 2275);
DISPLAY INVISIBLE (5175 2275);
FORCEADD OFFPAGE..4
(4650 2625);
FORCEPROP 2 LAST $XR0 304 
J 0
(4836 2625);
DISPLAY 0.638298 (4836 2625);
PAINT MONO (4836 2625);
FORCEPROP 2 LAST PATH I47
J 0
(4850 2675);
DISPLAY 1.021277 (4850 2675);
DISPLAY INVISIBLE (4850 2675);
FORCEPROP 1 LAST COMMENT_BODY TRUE
J 0
(4625 2525);
DISPLAY 0.872340 (4625 2525);
PAINT GREEN (4625 2525);
DISPLAY INVISIBLE (4625 2525);
FORCEPROP 1 LAST OFFPAGE TRUE
J 0
(4975 2500);
DISPLAY 0.872340 (4975 2500);
PAINT GREEN (4975 2500);
DISPLAY INVISIBLE (4975 2500);
FORCEPROP 2 LAST CDS_LIB standard
J 0
(4650 2625);
DISPLAY INVISIBLE (4650 2625);
FORCEADD UNIVERSAL_POWER..1
(4550 2775);
FORCEPROP 1 LAST HDL_POWER P12V_PSU
J 1
(4550 2825);
DISPLAY 0.723404 (4550 2825);
PAINT GREEN (4550 2825);
FORCEPROP 1 LAST PATH I48
J 0
(4600 2800);
DISPLAY 0.872340 (4600 2800);
PAINT AQUA (4600 2800);
DISPLAY INVISIBLE (4600 2800);
FORCEPROP 2 LAST CDS_LIB logical_power
J 0
(4550 2775);
DISPLAY INVISIBLE (4550 2775);
FORCEPROP 2 LAST ROOM AUX_SW
J 0
(4550 2875);
DISPLAY 0.617021 (4550 2875);
DISPLAY INVISIBLE (4550 2875);
FORCEPROP 2 LAST BOM_COST MIO_VRD_SB
J 0
(4550 2875);
DISPLAY 0.617021 (4550 2875);
PAINT PURPLE (4550 2875);
DISPLAY INVISIBLE (4550 2875);
FORCEADD MMBT3904..1
R 2
(925 125);
FORCEPROP 1 LAST PART_NUMBER BA039040039
J 2
(850 35);
DISPLAY 0.723404 (850 35);
PAINT GREEN (850 35);
DISPLAY INVISIBLE (850 35);
FORCEPROP 2 LAST VALUE MMBT3904    
J 2
(1025 175);
DISPLAY 1.021277 (1025 175);
FORCEPROP 2 LAST ROOM HSC1_BOM2
J 0
(400 250);
DISPLAY 1.021277 (400 250);
FORCEPROP 2 LAST PACK_TYPE SMLF
J 2
(850 125);
DISPLAY 1.021277 (850 125);
FORCEPROP 1 LAST MATERIAL EMPTY
J 2
(850 -15);
DISPLAY 0.723404 (850 -15);
PAINT GREEN (850 -15);
FORCEPROP 1 LAST LOCATION U365
J 2
(850 80);
DISPLAY 0.723404 (850 80);
PAINT GREEN (850 80);
FORCEPROP 0 LASTPIN (1025 125) $PN B
J 0
(1035 135);
DISPLAY 0.680851 (1035 135);
PAINT MONO (1035 135);
FORCEPROP 0 LASTPIN (875 25) $PN E
R 1
J 2
(865 15);
DISPLAY 0.680851 (865 15);
PAINT MONO (865 15);
FORCEPROP 0 LASTPIN (875 225) $PN C
R 1
J 0
(865 235);
DISPLAY 0.680851 (865 235);
PAINT MONO (865 235);
FORCEPROP 2 LAST CDS_LIB pure_quanta
J 2
(925 125);
DISPLAY INVISIBLE (925 125);
FORCEPROP 1 LAST PATH I49
J 2
(775 -20);
DISPLAY 0.723404 (775 -20);
PAINT GREEN (775 -20);
DISPLAY INVISIBLE (775 -20);
FORCEPROP 1 LAST NEEDS_NO_SIZE TRUE
J 2
(925 125);
DISPLAY 0.468085 (925 125);
PAINT GREEN (925 125);
DISPLAY INVISIBLE (925 125);
FORCEPROP 0 LAST $SEC 1
J 0
(850 225);
DISPLAY 0.680851 (850 225);
PAINT MONO (850 225);
DISPLAY INVISIBLE (850 225);
FORCEPROP 0 LAST CDS_SEC 1
J 0
(850 225);
DISPLAY 1.021277 (850 225);
DISPLAY INVISIBLE (850 225);
FORCEADD Q_RES..1
(1750 300);
FORCEPROP 1 LAST PART_NUMBER CS04992FB07
J 0
(1550 150);
DISPLAY 0.638298 (1550 150);
DISPLAY INVISIBLE (1550 150);
FORCEPROP 1 LAST TOLERANCE 1%
J 0
(1825 250);
DISPLAY 0.638298 (1825 250);
FORCEPROP 1 LAST WATTAGE 1/16W
J 2
(1700 250);
DISPLAY 0.638298 (1700 250);
FORCEPROP 2 LAST ROOM HSC1_BOM2
J 0
(1575 400);
DISPLAY 1.021277 (1575 400);
FORCEPROP 1 LAST VALUE 49.9
J 2
(2000 325);
DISPLAY 0.638298 (2000 325);
FORCEPROP 1 LAST PACK_TYPE 0402LF
J 0
(1550 200);
DISPLAY 0.638298 (1550 200);
FORCEPROP 1 LAST MATERIAL EMPTY
J 0
(1825 200);
DISPLAY 0.638298 (1825 200);
FORCEPROP 1 LAST LOCATION R4892
J 0
(1575 350);
DISPLAY 0.638298 (1575 350);
FORCEPROP 1 LASTPIN (1650 300) $PN 1
J 0
(1662 312);
DISPLAY 0.787234 (1662 312);
PAINT MONO (1662 312);
FORCEPROP 1 LASTPIN (1850 300) $PN 2
J 0
(1812 312);
DISPLAY 0.787234 (1812 312);
PAINT MONO (1812 312);
FORCEPROP 2 LAST CDS_LIB pure_quanta
J 0
(1750 300);
DISPLAY INVISIBLE (1750 300);
FORCEPROP 1 LAST PATH I5
J 0
(1700 450);
DISPLAY 0.978723 (1700 450);
PAINT WHITE (1700 450);
DISPLAY INVISIBLE (1700 450);
FORCEPROP 0 LAST $SEC 1
J 0
(1925 375);
DISPLAY 0.680851 (1925 375);
PAINT MONO (1925 375);
DISPLAY INVISIBLE (1925 375);
FORCEPROP 0 LAST CDS_SEC 1
J 0
(1800 475);
DISPLAY 1.021277 (1800 475);
DISPLAY INVISIBLE (1800 475);
FORCEADD GND..1
(2750 1600);
FORCEPROP 3 LASTPIN (2750 1650) SIG_NAME GND\g
J 0
(2760 1660);
DISPLAY 0.659574 (2760 1660);
PAINT MONO (2760 1660);
DISPLAY INVISIBLE (2760 1660);
FORCEPROP 1 LAST PATH I50
J 0
(2825 1600);
DISPLAY 0.872340 (2825 1600);
PAINT AQUA (2825 1600);
DISPLAY INVISIBLE (2825 1600);
FORCEPROP 2 LAST CDS_LIB logical_power
J 0
(2750 1600);
DISPLAY INVISIBLE (2750 1600);
FORCEPROP 1 LAST SIZE 1B
J 0
(2825 1550);
DISPLAY 0.872340 (2825 1550);
PAINT AQUA (2825 1550);
DISPLAY INVISIBLE (2825 1550);
FORCEPROP 1 LAST HDL_POWER GND
J 0
(2750 1750);
DISPLAY 1.170213 (2750 1750);
PAINT GREEN (2750 1750);
DISPLAY INVISIBLE (2750 1750);
FORCEADD CONN3_210HP1030BR1..1
R 2
(2475 1750);
PAINT AQUA (2475 1750);
FORCEPROP 1 LAST PART_NUMBER DFHD03MS213
J 2
(2400 1675);
DISPLAY 0.723404 (2400 1675);
PAINT WHITE (2400 1675);
DISPLAY INVISIBLE (2400 1675);
FORCEPROP 2 LAST VALUE CONN3_210-HP1-030BR1
J 2
(2425 1825);
DISPLAY 0.723404 (2425 1825);
PAINT AQUA (2425 1825);
FORCEPROP 2 LAST PART_TYPE THLF
J 2
(2425 1775);
DISPLAY 1.021277 (2425 1775);
FORCEPROP 1 LAST MATERIAL IO
J 2
(2400 1624);
DISPLAY 0.723404 (2400 1624);
PAINT SKYBLUE (2400 1624);
FORCEPROP 1 LAST $LOCATION JP10
J 2
(2400 1725);
DISPLAY 0.723404 (2400 1725);
PAINT AQUA (2400 1725);
FORCEPROP 0 LASTPIN (2675 1800) $PN 1
J 0
(2685 1810);
DISPLAY 0.680851 (2685 1810);
PAINT MONO (2685 1810);
FORCEPROP 0 LASTPIN (2675 1750) $PN 2
J 0
(2685 1760);
DISPLAY 0.680851 (2685 1760);
PAINT MONO (2685 1760);
FORCEPROP 0 LASTPIN (2675 1700) $PN 3
J 0
(2685 1710);
DISPLAY 0.680851 (2685 1710);
PAINT MONO (2685 1710);
FORCEPROP 1 LAST PATH I51
J 2
(2475 1750);
DISPLAY 0.723404 (2475 1750);
PAINT GREEN (2475 1750);
DISPLAY INVISIBLE (2475 1750);
FORCEPROP 2 LAST CDS_LIB pure_quanta
J 2
(2475 1750);
DISPLAY INVISIBLE (2475 1750);
FORCEPROP 1 LAST CDS_LMAN_SYM_OUTLINE -50,100,50,-100
J 2
(2475 1750);
DISPLAY 0.468085 (2475 1750);
PAINT GREEN (2475 1750);
DISPLAY INVISIBLE (2475 1750);
FORCEPROP 1 LAST NEEDS_NO_SIZE TRUE
J 2
(2475 1750);
DISPLAY 0.723404 (2475 1750);
PAINT GREEN (2475 1750);
DISPLAY INVISIBLE (2475 1750);
FORCEPROP 0 LAST CDS_LOCATION JP10
J 0
(2425 1875);
DISPLAY 1.021277 (2425 1875);
DISPLAY INVISIBLE (2425 1875);
FORCEPROP 0 LAST $SEC 1
J 0
(2425 1875);
DISPLAY 0.680851 (2425 1875);
PAINT MONO (2425 1875);
DISPLAY INVISIBLE (2425 1875);
FORCEPROP 0 LAST CDS_SEC 1
J 0
(2425 1875);
DISPLAY 1.021277 (2425 1875);
DISPLAY INVISIBLE (2425 1875);
FORCEADD Q_CAP..1
R 2
(2050 150);
FORCEPROP 1 LAST PART_NUMBER TMP_QCH21006K917
J 0
(2125 0);
DISPLAY 0.510638 (2125 0);
DISPLAY INVISIBLE (2125 0);
FORCEPROP 2 LAST ROOM HSC1_BOM2
J 0
(2125 275);
DISPLAY 1.021277 (2125 275);
FORCEPROP 1 LAST VALUE 1000PF
J 0
(2125 200);
DISPLAY 0.510638 (2125 200);
FORCEPROP 1 LAST VOLTAGE 50V
J 0
(2125 150);
DISPLAY 0.510638 (2125 150);
FORCEPROP 1 LAST TOLERANCE 10%
J 0
(2125 100);
DISPLAY 0.510638 (2125 100);
FORCEPROP 1 LAST MATERIAL EMPTY
J 0
(2125 50);
DISPLAY 0.510638 (2125 50);
FORCEPROP 1 LAST PACK_TYPE 0603
J 0
(2125 -50);
DISPLAY 0.510638 (2125 -50);
FORCEPROP 1 LAST LOCATION C2459
J 0
(2125 250);
DISPLAY 0.510638 (2125 250);
FORCEPROP 1 LASTPIN (2050 250) $PN 1
J 2
(2040 230);
DISPLAY 0.787234 (2040 230);
PAINT MONO (2040 230);
FORCEPROP 1 LASTPIN (2050 50) $PN 2
J 2
(2040 30);
DISPLAY 0.787234 (2040 30);
PAINT MONO (2040 30);
FORCEPROP 2 LAST CDS_LIB pure_quanta
J 0
(2050 150);
DISPLAY INVISIBLE (2050 150);
FORCEPROP 1 LAST PATH I6
J 2
(2000 300);
DISPLAY 0.978723 (2000 300);
PAINT WHITE (2000 300);
DISPLAY INVISIBLE (2000 300);
FORCEPROP 0 LAST $SEC 1
J 0
(2125 275);
DISPLAY 0.680851 (2125 275);
PAINT MONO (2125 275);
DISPLAY INVISIBLE (2125 275);
FORCEPROP 0 LAST CDS_SEC 1
J 0
(2000 300);
DISPLAY 1.021277 (2000 300);
DISPLAY INVISIBLE (2000 300);
FORCEADD UNIVERSAL_GND..1
(2275 425);
FORCEPROP 3 LASTPIN (2275 475) SIG_NAME GND\g
J 0
(2285 485);
DISPLAY 0.659574 (2285 485);
PAINT MONO (2285 485);
DISPLAY INVISIBLE (2285 485);
FORCEPROP 1 LAST PATH I7
J 0
(2350 425);
DISPLAY 0.872340 (2350 425);
PAINT AQUA (2350 425);
DISPLAY INVISIBLE (2350 425);
FORCEPROP 2 LAST CDS_LIB logical_power
J 0
(2275 425);
DISPLAY INVISIBLE (2275 425);
FORCEPROP 1 LAST HDL_POWER GND
J 1
(2300 350);
DISPLAY 0.702128 (2300 350);
PAINT GREEN (2300 350);
DISPLAY INVISIBLE (2300 350);
FORCEADD Q_CAP..1
(2275 625);
FORCEPROP 1 LAST PART_NUMBER CH4104K1B00
J 0
(2325 475);
DISPLAY 0.510638 (2325 475);
DISPLAY INVISIBLE (2325 475);
FORCEPROP 1 LAST PACK_TYPE 0402
J 0
(2325 425);
DISPLAY 0.510638 (2325 425);
FORCEPROP 1 LAST VOLTAGE 25V
J 0
(2325 625);
DISPLAY 0.510638 (2325 625);
FORCEPROP 1 LAST VALUE 0.1UF
J 0
(2325 675);
DISPLAY 0.510638 (2325 675);
FORCEPROP 1 LAST TOLERANCE 10%
J 0
(2325 575);
DISPLAY 0.510638 (2325 575);
FORCEPROP 2 LAST ROOM HSC1_BOM2
J 0
(2325 775);
DISPLAY 1.021277 (2325 775);
FORCEPROP 1 LAST MATERIAL EMPTY
J 0
(2325 525);
DISPLAY 0.510638 (2325 525);
FORCEPROP 1 LAST LOCATION C2458
J 0
(2325 725);
DISPLAY 0.702128 (2325 725);
FORCEPROP 1 LASTPIN (2275 725) $PN 1
J 0
(2285 705);
DISPLAY 0.808511 (2285 705);
PAINT WHITE (2285 705);
FORCEPROP 1 LASTPIN (2275 525) $PN 2
J 0
(2285 505);
DISPLAY 0.808511 (2285 505);
PAINT WHITE (2285 505);
FORCEPROP 2 LAST CDS_LIB pure_quanta
J 0
(2275 625);
DISPLAY INVISIBLE (2275 625);
FORCEPROP 1 LAST PATH I8
J 0
(2325 775);
DISPLAY 0.978723 (2325 775);
PAINT WHITE (2325 775);
DISPLAY INVISIBLE (2325 775);
FORCEPROP 0 LAST $SEC 1
J 0
(2325 775);
DISPLAY 0.680851 (2325 775);
PAINT MONO (2325 775);
DISPLAY INVISIBLE (2325 775);
FORCEPROP 0 LAST CDS_SEC 1
J 0
(2325 775);
DISPLAY 1.021277 (2325 775);
DISPLAY INVISIBLE (2325 775);
FORCEADD UNIVERSAL_POWER..1
(2275 1050);
FORCEPROP 3 LASTPIN (2275 1000) SIG_NAME P3V3_AUX\g
J 0
(2285 1010);
DISPLAY 0.659574 (2285 1010);
PAINT MONO (2285 1010);
DISPLAY INVISIBLE (2285 1010);
FORCEPROP 1 LAST HDL_POWER P3V3_AUX
J 1
(2275 1100);
DISPLAY 0.702128 (2275 1100);
PAINT GREEN (2275 1100);
FORCEPROP 1 LAST PATH I9
J 0
(2325 1075);
DISPLAY 0.872340 (2325 1075);
PAINT AQUA (2325 1075);
DISPLAY INVISIBLE (2325 1075);
FORCEPROP 2 LAST CDS_LIB logical_power
J 0
(2275 1050);
DISPLAY INVISIBLE (2275 1050);
FORCEADD QUANTA_TITLE_BLOCK_C..1
(6125 -1825);
FORCEPROP 0 LAST CDS_CON_LAST_MODIFIED Fri Aug 25 14:05:17 2023
J 0
(4240 -1810);
DISPLAY INVISIBLE (4240 -1810);
FORCEPROP 1 LAST CUSTOM_TXT_CDS <CON_LAST_MODIFIED>
J 0
(4240 -1810);
DISPLAY 0.978723 (4240 -1810);
FORCEPROP 2 LAST CUSTOM_TXT_CDS <XR_PAGE_TITLE>
J 0
(-1765 3425);
DISPLAY 0.638298 (-1765 3425);
PAINT PINK (-1765 3425);
DISPLAY INVISIBLE (-1765 3425);
FORCEPROP 1 LAST CUSTOM_TXT_CDS <NAME_2>
J 0
(2950 -1775);
FORCEPROP 1 LAST CUSTOM_TXT_CDS <NAME_1>
J 0
(2950 -1650);
FORCEPROP 1 LAST CUSTOM_TXT_CDS <Q_NUMBER>
J 0
(4722 -1722);
DISPLAY 1.212766 (4722 -1722);
FORCEPROP 1 LAST CUSTOM_TXT_CDS <Q_PROJ>
J 0
(3743 -1723);
DISPLAY 1.212766 (3743 -1723);
FORCEPROP 1 LAST CUSTOM_TXT_CDS <Q_REV>
J 0
(5941 -1722);
DISPLAY 1.212766 (5941 -1722);
FORCEPROP 1 LAST CUSTOM_TXT_CDS <CON_PAGE_NUM> OF <CON_TOTAL_PAGES>
J 0
(5679 -1807);
DISPLAY 0.978723 (5679 -1807);
FORCEPROP 1 LAST Q_TITLE HSC MODULE(2/4)
J 0
(-3241 -1799);
DISPLAY 2.446809 (-3241 -1799);
PAINT GREEN (-3241 -1799);
FORCEPROP 1 LAST Q_DEPT 
J 1
(2362 -1776);
DISPLAY 1.957447 (2362 -1776);
PAINT GREEN (2362 -1776);
FORCEPROP 2 LAST CDS_XR_PAGE_TITLE CR-305 : @S9S_MB_2U_LIB.S9S_MB_2U(SCH_1):PAGE305
J 0
(-1765 3425);
DISPLAY 0.638298 (-1765 3425);
PAINT PINK (-1765 3425);
DISPLAY INVISIBLE (-1765 3425);
FORCEPROP 2 LAST PAGE_BORDER TRUE
J 0
(-1765 3425);
DISPLAY 0.638298 (-1765 3425);
PAINT PINK (-1765 3425);
DISPLAY INVISIBLE (-1765 3425);
FORCEPROP 1 LAST COMMENT_BODY TRUE
J 0
(6137 -1838);
DISPLAY 0.978723 (6137 -1838);
PAINT PEACH (6137 -1838);
DISPLAY INVISIBLE (6137 -1838);
FORCEPROP 1 LAST CDS_LMAN_SYM_OUTLINE -9475,6775,100,-125
J 0
(6125 -1825);
DISPLAY 0.468085 (6125 -1825);
PAINT GREEN (6125 -1825);
DISPLAY INVISIBLE (6125 -1825);
FORCEPROP 2 LAST CDS_LIB pure_quanta
J 0
(6125 -1825);
DISPLAY INVISIBLE (6125 -1825);
FORCEADD DNS..1
(900 75);
PAINT RED (900 75);
FORCEPROP 1 LAST COMMENT_BODY TRUE
R 1
J 0
(975 -150);
DISPLAY 0.872340 (975 -150);
PAINT GREEN (975 -150);
DISPLAY INVISIBLE (975 -150);
FORCEPROP 2 LAST CDS_LIB mstr_misc
J 0
(900 75);
DISPLAY INVISIBLE (900 75);
FORCEADD DNS..1
(3225 175);
PAINT RED (3225 175);
FORCEPROP 2 LAST CDS_LIB mstr_misc
J 0
(3225 175);
DISPLAY INVISIBLE (3225 175);
FORCEPROP 1 LAST COMMENT_BODY TRUE
R 1
J 0
(3300 -50);
DISPLAY 0.872340 (3300 -50);
PAINT GREEN (3300 -50);
DISPLAY INVISIBLE (3300 -50);
FORCEADD DNS..1
(4800 700);
PAINT RED (4800 700);
FORCEPROP 2 LAST CDS_LIB mstr_misc
J 0
(4800 700);
DISPLAY INVISIBLE (4800 700);
FORCEPROP 1 LAST COMMENT_BODY TRUE
R 1
J 0
(4875 475);
DISPLAY 0.872340 (4875 475);
PAINT GREEN (4875 475);
DISPLAY INVISIBLE (4875 475);
FORCEADD DNS..1
(4475 425);
PAINT RED (4475 425);
FORCEPROP 2 LAST CDS_LIB mstr_misc
J 0
(4475 425);
DISPLAY INVISIBLE (4475 425);
FORCEPROP 1 LAST COMMENT_BODY TRUE
R 1
J 0
(4550 200);
DISPLAY 0.872340 (4550 200);
PAINT GREEN (4550 200);
DISPLAY INVISIBLE (4550 200);
FORCEADD DNS..1
(4475 325);
PAINT RED (4475 325);
FORCEPROP 2 LAST CDS_LIB mstr_misc
J 0
(4475 325);
DISPLAY INVISIBLE (4475 325);
FORCEPROP 1 LAST COMMENT_BODY TRUE
R 1
J 0
(4550 100);
DISPLAY 0.872340 (4550 100);
PAINT GREEN (4550 100);
DISPLAY INVISIBLE (4550 100);
FORCEADD DNS..1
(4500 225);
PAINT RED (4500 225);
FORCEPROP 2 LAST CDS_LIB mstr_misc
J 0
(4500 225);
DISPLAY INVISIBLE (4500 225);
FORCEPROP 1 LAST COMMENT_BODY TRUE
R 1
J 0
(4575 0);
DISPLAY 0.872340 (4575 0);
PAINT GREEN (4575 0);
DISPLAY INVISIBLE (4575 0);
FORCEADD DNS..1
(4775 -125);
PAINT RED (4775 -125);
FORCEPROP 2 LAST CDS_LIB mstr_misc
J 0
(4775 -125);
DISPLAY INVISIBLE (4775 -125);
FORCEPROP 1 LAST COMMENT_BODY TRUE
R 1
J 0
(4850 -350);
DISPLAY 0.872340 (4850 -350);
PAINT GREEN (4850 -350);
DISPLAY INVISIBLE (4850 -350);
FORCEADD DNS..1
(3425 -300);
PAINT RED (3425 -300);
FORCEPROP 2 LAST CDS_LIB mstr_misc
J 0
(3425 -300);
DISPLAY INVISIBLE (3425 -300);
FORCEPROP 1 LAST COMMENT_BODY TRUE
R 1
J 0
(3500 -525);
DISPLAY 0.872340 (3500 -525);
PAINT GREEN (3500 -525);
DISPLAY INVISIBLE (3500 -525);
FORCEADD DNS..1
(3675 2450);
PAINT RED (3675 2450);
FORCEPROP 2 LAST CDS_LIB mstr_misc
J 0
(3675 2450);
DISPLAY INVISIBLE (3675 2450);
FORCEPROP 1 LAST COMMENT_BODY TRUE
R 1
J 0
(3750 2225);
DISPLAY 0.872340 (3750 2225);
PAINT GREEN (3750 2225);
DISPLAY INVISIBLE (3750 2225);
FORCEADD DNS..1
(2250 625);
PAINT RED (2250 625);
FORCEPROP 2 LAST CDS_LIB mstr_misc
J 0
(2250 625);
DISPLAY INVISIBLE (2250 625);
FORCEPROP 1 LAST COMMENT_BODY TRUE
R 1
J 0
(2325 400);
DISPLAY 0.872340 (2325 400);
PAINT GREEN (2325 400);
DISPLAY INVISIBLE (2325 400);
FORCEADD DNS..1
(2075 175);
PAINT RED (2075 175);
FORCEPROP 2 LAST CDS_LIB mstr_misc
J 0
(2075 175);
DISPLAY INVISIBLE (2075 175);
FORCEPROP 1 LAST COMMENT_BODY TRUE
R 1
J 0
(2150 -50);
DISPLAY 0.872340 (2150 -50);
PAINT GREEN (2150 -50);
DISPLAY INVISIBLE (2150 -50);
FORCEADD DNS..1
(1800 300);
PAINT RED (1800 300);
FORCEPROP 2 LAST CDS_LIB mstr_misc
J 0
(1800 300);
DISPLAY INVISIBLE (1800 300);
FORCEPROP 1 LAST COMMENT_BODY TRUE
R 1
J 0
(1875 75);
DISPLAY 0.872340 (1875 75);
PAINT GREEN (1875 75);
DISPLAY INVISIBLE (1875 75);
FORCEADD DNS..1
(1725 -25);
PAINT RED (1725 -25);
FORCEPROP 2 LAST CDS_LIB mstr_misc
J 0
(1725 -25);
DISPLAY INVISIBLE (1725 -25);
FORCEPROP 1 LAST COMMENT_BODY TRUE
R 1
J 0
(1800 -250);
DISPLAY 0.872340 (1800 -250);
PAINT GREEN (1800 -250);
DISPLAY INVISIBLE (1800 -250);
FORCEADD DNS..1
(4425 1925);
PAINT RED (4425 1925);
FORCEPROP 1 LAST COMMENT_BODY TRUE
R 1
J 0
(4500 1700);
DISPLAY 0.872340 (4500 1700);
PAINT GREEN (4500 1700);
DISPLAY INVISIBLE (4500 1700);
FORCEPROP 2 LAST CDS_LIB mstr_misc
J 0
(4425 1925);
DISPLAY INVISIBLE (4425 1925);
WIRE 16 -1 (4425 2225)(5175 2225);
WIRE 16 -1 (4425 2050)(4425 2225);
WIRE 16 -1 (3950 2225)(4425 2225);
FORCEPROP 2 LAST SIG_NAME P12V_AUX
J 0
(4040 2235);
DISPLAY 0.723404 (4040 2235);
WIRE 16 -1 (4800 925)(4800 850);
WIRE 16 -1 (2275 1000)(2275 925);
WIRE 16 -1 (4800 50)(4800 0);
WIRE 16 -1 (4550 2675)(4550 2725);
WIRE 16 -1 (3950 2675)(4550 2675);
FORCEPROP 2 LAST SIG_NAME P12V_PSU
J 0
(4040 2685);
DISPLAY 0.723404 (4040 2685);
WIRE 16 -1 (2950 2725)(2950 2675);
WIRE 16 -1 (4425 1850)(4425 1825);
WIRE 16 -1 (4050 2050)(4050 2175);
WIRE 16 -1 (3700 100)(3700 25);
WIRE 16 -1 (3600 100)(3700 100);
WIRE 16 -1 (2275 525)(2275 475);
WIRE 16 -1 (3200 1900)(3200 2025);
WIRE 16 -1 (2750 1700)(2750 1650);
WIRE 16 -1 (2750 1700)(2675 1700);
WIRE 16 -1 (3200 2025)(3350 2025);
WIRE 16 -1 (3200 2025)(3200 2075);
WIRE 16 -1 (3350 2075)(3200 2075);
WIRE 16 -1 (3200 2075)(3200 2225);
WIRE 16 -1 (3200 2225)(3350 2225);
WIRE 16 -1 (2950 2675)(3350 2675);
WIRE 16 -1 (4050 2175)(3950 2175);
WIRE 16 -1 (2675 400)(2800 400);
WIRE 16 -1 (2675 925)(2675 400);
WIRE 16 -1 (2675 925)(2275 925);
WIRE 16 -1 (2275 725)(2275 925);
WIRE 16 -1 (2025 2375)(2700 2375);
FORCEPROP 2 LAST SIG_NAME SMB_SML1_PMBUS_HSC_MODULE_SCL
J 0
(2265 2385);
DISPLAY 0.723404 (2265 2385);
WIRE 16 -1 (3350 2375)(2700 2375);
WIRE 16 -1 (2700 1800)(2675 1800);
WIRE 16 -1 (2700 1800)(2700 2375);
WIRE 16 -1 (2025 2325)(2750 2325);
FORCEPROP 2 LAST SIG_NAME SMB_SML1_PMBUS_HSC_MODULE_SDA
J 0
(2265 2335);
DISPLAY 0.723404 (2265 2335);
WIRE 16 -1 (2750 2325)(3350 2325);
WIRE 16 -1 (2750 1750)(2750 2325);
WIRE 16 -1 (2675 1750)(2750 1750);
WIRE 16 -1 (3350 2275)(2475 2275);
FORCEPROP 2 LAST SIG_NAME IRQ_SML1_PMBUS_ALERT_N
J 0
(2490 2285);
DISPLAY 0.723404 (2490 2285);
WIRE 16 273 (425 -125)(425 375);
WIRE 16 273 (425 375)(1525 375);
WIRE 16 273 (425 -125)(1525 -125);
WIRE 16 273 (1525 -125)(1525 375);
WIRE 16 -1 (3950 2375)(4600 2375);
FORCEPROP 2 LAST SIG_NAME P12V_HSC_ADC_P
J 0
(4040 2385);
DISPLAY 0.723404 (4040 2385);
WIRE 16 -1 (2475 2575)(3350 2575);
FORCEPROP 2 LAST SIG_NAME HSC_EN
J 0
(2490 2585);
DISPLAY 0.723404 (2490 2585);
WIRE 16 -1 (825 2325)(1825 2325);
FORCEPROP 2 LAST SIG_NAME SMB_SML1_PMBUS_HSC_SDA
J 0
(840 2335);
DISPLAY 0.723404 (840 2335);
WIRE 16 -1 (2475 2625)(3350 2625);
FORCEPROP 2 LAST SIG_NAME IRQ_HSC_FAULT_N
J 0
(2490 2635);
DISPLAY 0.723404 (2490 2635);
WIRE 16 -1 (2475 2525)(3350 2525);
FORCEPROP 2 LAST SIG_NAME MB0_P12V_STBY_PWRGD
J 0
(2490 2535);
DISPLAY 0.723404 (2490 2535);
WIRE 16 -1 (2050 300)(2050 250);
WIRE 16 -1 (2800 300)(2050 300);
FORCEPROP 2 LAST SIG_NAME P12V_HSC_TEMP_D+
J 0
(2265 310);
DISPLAY 0.638298 (2265 310);
PAINT WHITE (2265 310);
WIRE 16 -1 (1850 300)(2050 300);
WIRE 16 -1 (1025 300)(1025 125);
WIRE 16 -1 (1650 300)(1025 300);
FORCEPROP 2 LAST SIG_NAME P12V_HSC_TEMP_R
J 0
(940 310);
DISPLAY 0.723404 (940 310);
WIRE 16 -1 (875 300)(1025 300);
WIRE 16 -1 (875 225)(875 300);
WIRE 16 -1 (825 2375)(1825 2375);
FORCEPROP 2 LAST SIG_NAME SMB_SML1_PMBUS_HSC_SCL
J 0
(840 2385);
DISPLAY 0.723404 (840 2385);
WIRE 16 -1 (3950 2575)(4600 2575);
FORCEPROP 2 LAST SIG_NAME P12V_HSC_SENSE1_N
J 0
(4040 2585);
DISPLAY 0.723404 (4040 2585);
WIRE 16 -1 (3950 2525)(4600 2525);
FORCEPROP 2 LAST SIG_NAME P12V_HSC_SENSE2_P
J 0
(4040 2535);
DISPLAY 0.723404 (4040 2535);
WIRE 16 -1 (3950 2475)(4600 2475);
FORCEPROP 2 LAST SIG_NAME P12V_HSC_SENSE2_N
J 0
(4040 2485);
DISPLAY 0.723404 (4040 2485);
WIRE 16 -1 (3950 2625)(4600 2625);
FORCEPROP 2 LAST SIG_NAME P12V_HSC_SENSE1_P
J 0
(4040 2635);
DISPLAY 0.723404 (4040 2635);
WIRE 16 -1 (3950 2425)(4600 2425);
FORCEPROP 2 LAST SIG_NAME P12V_HSC_ADC_N
J 0
(4040 2435);
DISPLAY 0.723404 (4040 2435);
WIRE 16 -1 (3950 2325)(4600 2325);
FORCEPROP 2 LAST SIG_NAME P12V_HSC_GATE1
J 0
(4040 2335);
DISPLAY 0.723404 (4040 2335);
WIRE 16 -1 (3950 2275)(4600 2275);
FORCEPROP 2 LAST SIG_NAME P12V_HSC_GATE2
J 0
(4040 2285);
DISPLAY 0.723404 (4040 2285);
WIRE 16 -1 (4575 400)(5325 400);
FORCEPROP 2 LAST SIG_NAME SMB_LM75_0_3V3AUX_SCL
J 0
(4840 410);
DISPLAY 0.510638 (4840 410);
PAINT WHITE (4840 410);
WIRE 16 -1 (3525 -325)(4800 -325);
FORCEPROP 2 LAST SIG_NAME P12V_HSC_T_CRIT_R_N
J 0
(4190 -315);
DISPLAY 0.510638 (4190 -315);
PAINT WHITE (4190 -315);
WIRE 16 -1 (4800 -325)(5350 -325);
WIRE 16 -1 (4800 -200)(4800 -325);
WIRE 16 273 (3900 -825)(5900 -825);
WIRE 16 273 (5900 -825)(5900 -525);
WIRE 16 273 (3900 -825)(3900 -525);
WIRE 16 273 (3900 -525)(5900 -525);
WIRE 16 -1 (1625 -50)(875 -50);
FORCEPROP 2 LAST SIG_NAME P12V_HSC_TEMP_E
J 0
(965 -40);
DISPLAY 0.723404 (965 -40);
WIRE 16 -1 (875 25)(875 -50);
WIRE 16 -1 (3325 -325)(2625 -325);
FORCEPROP 2 LAST SIG_NAME P12V_HSC_T_CRIT_N
J 0
(2665 -315);
DISPLAY 0.638298 (2665 -315);
PAINT WHITE (2665 -315);
WIRE 16 -1 (2625 100)(2625 -325);
WIRE 16 -1 (2800 100)(2625 100);
WIRE 16 -1 (2800 200)(2350 200);
FORCEPROP 2 LAST SIG_NAME P12V_HSC_TEMP_D-
J 0
(2265 210);
DISPLAY 0.638298 (2265 210);
PAINT WHITE (2265 210);
WIRE 16 -1 (2350 200)(2350 -50);
WIRE 16 -1 (2350 -50)(2050 -50);
WIRE 16 -1 (2050 -50)(2050 50);
WIRE 16 -1 (1825 -50)(2050 -50);
WIRE 16 -1 (4575 300)(5325 300);
FORCEPROP 2 LAST SIG_NAME SMB_LM75_0_3V3AUX_SDA
J 0
(4840 310);
DISPLAY 0.510638 (4840 310);
PAINT WHITE (4840 310);
WIRE 16 -1 (3350 2475)(2475 2475);
FORCEPROP 2 LAST SIG_NAME HSC_CSOUT
J 0
(2490 2485);
DISPLAY 0.808511 (2490 2485);
WIRE 16 -1 (4375 400)(3600 400);
FORCEPROP 2 LAST SIG_NAME P12V_HSC_TEMP_SCL
J 0
(3690 410);
DISPLAY 0.510638 (3690 410);
PAINT WHITE (3690 410);
WIRE 16 -1 (3600 300)(4375 300);
FORCEPROP 2 LAST SIG_NAME P12V_HSC_TEMP_SDA
J 0
(3690 310);
DISPLAY 0.510638 (3690 310);
PAINT WHITE (3690 310);
WIRE 16 -1 (4375 200)(3600 200);
FORCEPROP 2 LAST SIG_NAME P12V_HSC_TEMP_ALERT_N
J 0
(3690 210);
DISPLAY 0.510638 (3690 210);
PAINT WHITE (3690 210);
WIRE 16 -1 (4575 200)(4800 200);
WIRE 16 -1 (4800 200)(5350 200);
FORCEPROP 2 LAST SIG_NAME P12V_HSC_TEMP_ALERT_R_N
J 0
(4840 210);
DISPLAY 0.404255 (4840 210);
PAINT WHITE (4840 210);
WIRE 16 -1 (4800 650)(4800 200);
WIRE 16 -1 (2475 2425)(3350 2425);
FORCEPROP 2 LAST SIG_NAME HSC_TYPE_ADC
J 0
(2490 2435);
DISPLAY 0.808511 (2490 2435);
DOT 1 (1025 300);
DOT 1 (2050 -50);
DOT 1 (2050 300);
DOT 1 (2275 925);
DOT 1 (4800 -325);
DOT 1 (4800 200);
DOT 1 (3200 2075);
DOT 1 (4425 2225);
DOT 1 (3200 2025);
DOT 1 (2700 2375);
DOT 1 (2750 2325);
FORCENOTE
U365 CLOSE TO MOSFET
(650 400) 0;
DISPLAY LEFT (650 400);
DISPLAY 1.021277 (650 400);
FORCENOTE
U345
(3925 -600) 0;
DISPLAY LEFT (3925 -600);
DISPLAY 1.021277 (3925 -600);
FORCENOTE
MAIN SOURCE:AL007718001 (NCT7718W(MSOP))
(3925 -675) 0;
DISPLAY LEFT (3925 -675);
DISPLAY 1.021277 (3925 -675);
FORCENOTE
2ND SOURCE:AL000788001 (G788P81U(MSOP8))
(3925 -750) 0;
DISPLAY LEFT (3925 -750);
DISPLAY 1.021277 (3925 -750);
FORCENOTE
LTC4287=1.5V
(1825 1975) 0;
DISPLAY LEFT (1825 1975);
DISPLAY 1.021277 (1825 1975);
FORCENOTE
LTC4282=1.0V
(1825 2050) 0;
DISPLAY LEFT (1825 2050);
DISPLAY 1.021277 (1825 2050);
QUIT
